# TIMECARD (Time Appliance Project (Time Card)) — schematic netlist excerpt (pin names and nets, part order shuffled) for the footprints in the layout excerpt that follows; sources: Cadence DE-HDL packaged netlist, KiCad conversion of R4006-B0001-02_R01.brd

R47  RESISTOR  10KOHM 1%  pkg SMC_0402R_H016  page 32 : \1\ = XP3R3V ; \2\ = XP5R0V_PG
R77  RESISTOR  33OHM 1%  pkg SMC_0402R_H016  page 20 : \1\ = BNO080_I2C_SCL ; \2\ = R_BNO080_I2C_SCL

(kicad_pcb
	(version 20260206)
	(generator "pcbnew")
	(generator_version "10.0")
	(general
		(thickness 1.6)
		(legacy_teardrops no)
	)
	(paper "A4")
	(title_block
		(title "timecard-production-celestica-r4006 — R4006-B0001-02_R01.brd")
		(comment 1 "Time Appliance Project (Time Card) / footprints 962-963 of 1113")
	)
	(layers
		(0 "F.Cu" signal "TOP")
		(4 "In1.Cu" signal "L02_GND1")
		(6 "In2.Cu" signal "L03_SIG1")
		(8 "In3.Cu" signal "L04_GND2")
		(10 "In4.Cu" signal "L05_VCC1")
		(12 "In5.Cu" signal "L06_VCC2")
		(14 "In6.Cu" signal "L07_GND3")
		(16 "In7.Cu" signal "L08_SIG2")
		(18 "In8.Cu" signal "L09_GND4")
		(2 "B.Cu" signal "BOTTOM")
		(9 "F.Adhes" user "F.Adhesive")
		(11 "B.Adhes" user "B.Adhesive")
		(13 "F.Paste" user "Package Geometry/Pastemask Top")
		(15 "B.Paste" user "Package Geometry/Pastemask Bottom")
		(5 "F.SilkS" user "Ref Des/Silkscreen Top")
		(7 "B.SilkS" user "Ref Des/Silkscreen Bottom")
		(1 "F.Mask" user "Board Geometry/Soldermask Top")
		(3 "B.Mask" user "Board Geometry/Soldermask Bottom")
		(17 "Dwgs.User" user "User.Drawings")
		(19 "Cmts.User" user "User.Comments")
		(21 "Eco1.User" user "User.Eco1")
		(23 "Eco2.User" user "User.Eco2")
		(25 "Edge.Cuts" user "Board Geometry/Outline")
		(27 "Margin" user)
		(31 "F.CrtYd" user "Package Geometry/Place Bound Top")
		(29 "B.CrtYd" user "Package Geometry/Place Bound Bottom")
		(35 "F.Fab" user "Ref Des/Assembly Top")
		(33 "B.Fab" user "Ref Des/Assembly Bottom")
	)
	(footprint ""
		(layer "B.Cu")
		(at 85.09 -56.134 180)
		(property "Reference" "R77"
			(at 2.032 -1.18237 0)
			(unlocked yes)
			(layer "B.SilkS")
			(effects
				(font
					(size 0.7874 0.5842)
					(thickness 0.1524)
				)
				(justify mirror)
			)
		)
		(property "Value" "VAL*"
			(at -0.02032 2.13233 180)
			(unlocked yes)
			(layer "B.Fab")
			(hide yes)
			(effects
				(font
					(size 0.7874 0.5842)
					(thickness 0.1524)
				)
				(justify mirror)
			)
		)
		(property "Device Type" "RESISTOR-G155-133R0-01,33OHM,1%"
			(at -0.008382 1.210564 180)
			(unlocked yes)
			(layer "B.Fab")
			(hide yes)
			(effects
				(font
					(size 0.7874 0.5842)
					(thickness 0.1524)
				)
				(justify mirror)
			)
		)
		(property "User Part Number" "PARTNUM*"
			(at -0.02032 4.024884 180)
			(unlocked yes)
			(layer "Cmts.User")
			(hide yes)
			(effects
				(font
					(size 0.7874 0.5842)
					(thickness 0.1524)
				)
				(justify mirror)
			)
		)
		(property "Tolerance" "TOL*"
			(at -0.044704 3.05435 180)
			(unlocked yes)
			(layer "Cmts.User")
			(hide yes)
			(effects
				(font
					(size 0.7874 0.5842)
					(thickness 0.1524)
				)
				(justify mirror)
			)
		)
		(duplicate_pad_numbers_are_jumpers no)
		(fp_line
			(start 1.143 0.5588)
			(end -1.143 0.5588)
			(stroke
				(width 0.1)
				(type default)
			)
			(layer "B.SilkS")
		)
		(fp_line
			(start 1.143 -0.5588)
			(end 1.143 0.5588)
			(stroke
				(width 0.1)
				(type default)
			)
			(layer "B.SilkS")
		)
		(fp_line
			(start -1.143 0.5588)
			(end -1.143 -0.5588)
			(stroke
				(width 0.1)
				(type default)
			)
			(layer "B.SilkS")
		)
		(fp_line
			(start -1.143 -0.5588)
			(end 1.143 -0.5588)
			(stroke
				(width 0.1)
				(type default)
			)
			(layer "B.SilkS")
		)
		(fp_rect
			(start 1.143 -0.5588)
			(end -1.143 0.5588)
			(stroke
				(width 0)
				(type default)
			)
			(fill no)
			(layer "B.CrtYd")
		)
		(fp_line
			(start 0.508 0.3048)
			(end -0.508 0.3048)
			(stroke
				(width 0.1)
				(type default)
			)
			(layer "B.Fab")
		)
		(fp_line
			(start 0.508 -0.3048)
			(end 0.508 0.3048)
			(stroke
				(width 0.1)
				(type default)
			)
			(layer "B.Fab")
		)
		(fp_line
			(start -0.508 0.3048)
			(end -0.508 -0.3048)
			(stroke
				(width 0.1)
				(type default)
			)
			(layer "B.Fab")
		)
		(fp_line
			(start -0.508 -0.3048)
			(end 0.508 -0.3048)
			(stroke
				(width 0.1)
				(type default)
			)
			(layer "B.Fab")
		)
		(pad "1" smd rect
			(at 0.5334 0)
			(size 0.7112 0.6096)
			(layers "B.Cu" "B.Mask" "B.Paste")
			(net "BNO080_I2C_SCL")
		)
		(pad "2" smd rect
			(at -0.5334 0)
			(size 0.7112 0.6096)
			(layers "B.Cu" "B.Mask" "B.Paste")
			(net "R_BNO080_I2C_SCL")
		)
		(zone
			(layer "B.Cu")
			(hatch none 0.5)
			(connect_pads
				(clearance 0)
			)
			(min_thickness 0.25)
			(keepout
				(tracks allowed)
				(vias not_allowed)
				(pads allowed)
				(copperpour not_allowed)
				(footprints allowed)
			)
			(placement
				(enabled no)
				(sheetname "")
			)
			(fill
				(thermal_gap 0.5)
				(thermal_bridge_width 0.5)
				(island_removal_mode 0)
			)
			(polygon
				(pts
					(xy 85.0138 -55.8292) (xy 85.1662 -55.8292) (xy 85.1662 -56.4388) (xy 85.0138 -56.4388)
				)
			)
		)
	)
	(footprint ""
		(layer "B.Cu")
		(at 36.7284 -97.8154 180)
		(property "Reference" "R47"
			(at 3.8354 -0.69977 0)
			(unlocked yes)
			(layer "B.SilkS")
			(effects
				(font
					(size 0.7874 0.5842)
					(thickness 0.1524)
				)
				(justify mirror)
			)
		)
		(property "Value" "VAL*"
			(at -0.02032 2.13233 180)
			(unlocked yes)
			(layer "B.Fab")
			(hide yes)
			(effects
				(font
					(size 0.7874 0.5842)
					(thickness 0.1524)
				)
				(justify mirror)
			)
		)
		(property "Tolerance" "TOL*"
			(at -0.044704 3.05435 180)
			(unlocked yes)
			(layer "Cmts.User")
			(hide yes)
			(effects
				(font
					(size 0.7874 0.5842)
					(thickness 0.1524)
				)
				(justify mirror)
			)
		)
		(property "User Part Number" "PARTNUM*"
			(at -0.02032 4.024884 180)
			(unlocked yes)
			(layer "Cmts.User")
			(hide yes)
			(effects
				(font
					(size 0.7874 0.5842)
					(thickness 0.1524)
				)
				(justify mirror)
			)
		)
		(property "Device Type" "RESISTOR-G155-11002-01,10KOHM,A"
			(at -0.008382 1.210564 180)
			(unlocked yes)
			(layer "B.Fab")
			(hide yes)
			(effects
				(font
					(size 0.7874 0.5842)
					(thickness 0.1524)
				)
				(justify mirror)
			)
		)
		(duplicate_pad_numbers_are_jumpers no)
		(fp_line
			(start 1.143 0.5588)
			(end -1.143 0.5588)
			(stroke
				(width 0.1)
				(type default)
			)
			(layer "B.SilkS")
		)
		(fp_line
			(start 1.143 -0.5588)
			(end 1.143 0.5588)
			(stroke
				(width 0.1)
				(type default)
			)
			(layer "B.SilkS")
		)
		(fp_line
			(start -1.143 0.5588)
			(end -1.143 -0.5588)
			(stroke
				(width 0.1)
				(type default)
			)
			(layer "B.SilkS")
		)
		(fp_line
			(start -1.143 -0.5588)
			(end 1.143 -0.5588)
			(stroke
				(width 0.1)
				(type default)
			)
			(layer "B.SilkS")
		)
		(fp_poly
			(pts
				(xy 1.143 0.5588) (xy -1.143 0.5588) (xy -1.143 -0.5588) (xy 1.143 -0.5588)
			)
			(stroke
				(width 0)
				(type default)
			)
			(fill no)
			(layer "B.CrtYd")
		)
		(fp_line
			(start 0.508 0.3048)
			(end -0.508 0.3048)
			(stroke
				(width 0.1)
				(type default)
			)
			(layer "B.Fab")
		)
		(fp_line
			(start 0.508 -0.3048)
			(end 0.508 0.3048)
			(stroke
				(width 0.1)
				(type default)
			)
			(layer "B.Fab")
		)
		(fp_line
			(start -0.508 0.3048)
			(end -0.508 -0.3048)
			(stroke
				(width 0.1)
				(type default)
			)
			(layer "B.Fab")
		)
		(fp_line
			(start -0.508 -0.3048)
			(end 0.508 -0.3048)
			(stroke
				(width 0.1)
				(type default)
			)
			(layer "B.Fab")
		)
		(pad "1" smd rect
			(at 0.5334 0)
			(size 0.7112 0.6096)
			(layers "B.Cu" "B.Mask" "B.Paste")
			(net "XP3R3V")
		)
		(pad "2" smd rect
			(at -0.5334 0)
			(size 0.7112 0.6096)
			(layers "B.Cu" "B.Mask" "B.Paste")
			(net "XP5R0V_PG")
		)
		(zone
			(layer "B.Cu")
			(hatch none 0.5)
			(connect_pads
				(clearance 0)
			)
			(min_thickness 0.25)
			(keepout
				(tracks allowed)
				(vias not_allowed)
				(pads allowed)
				(copperpour not_allowed)
				(footprints allowed)
			)
			(placement
				(enabled no)
				(sheetname "")
			)
			(fill
				(thermal_gap 0.5)
				(thermal_bridge_width 0.5)
				(island_removal_mode 0)
			)
			(polygon
				(pts
					(xy 36.6522 -98.1202) (xy 36.6522 -97.5106) (xy 36.8046 -97.5106) (xy 36.8046 -98.1202)
				)
			)
		)
		(zone
			(layer "B.Cu")
			(hatch none 0.5)
			(connect_pads
				(clearance 0)
			)
			(min_thickness 0.25)
			(keepout
				(tracks not_allowed)
				(vias allowed)
				(pads allowed)
				(copperpour not_allowed)
				(footprints allowed)
			)
			(placement
				(enabled no)
				(sheetname "")
			)
			(fill
				(thermal_gap 0.5)
				(thermal_bridge_width 0.5)
				(island_removal_mode 0)
			)
			(polygon
				(pts
					(xy 36.6522 -98.1202) (xy 36.6522 -97.5106) (xy 36.8046 -97.5106) (xy 36.8046 -98.1202)
				)
			)
		)
	)
)
